(kicad_pcb
	(version 20260206)
	(generator "pcbnew")
	(generator_version "10.0")
	(general
		(thickness 1.6)
		(legacy_teardrops no)
	)
	(paper "A4")
	(title_block
		(title "fcb — Lightning_FCB_BRD.brd")
		(comment 1 "Lightning (Wiwynn / Facebook NVMe JBOF) / footprints 438-440 of 495")
	)
	(layers
		(0 "F.Cu" signal "TOP")
		(4 "In1.Cu" signal "L2GND")
		(6 "In2.Cu" signal "L3VCC")
		(2 "B.Cu" signal "BOTTOM")
		(9 "F.Adhes" user "F.Adhesive")
		(11 "B.Adhes" user "B.Adhesive")
		(13 "F.Paste" user "Package Geometry/Pastemask Top")
		(15 "B.Paste" user "Package Geometry/Pastemask Bottom")
		(5 "F.SilkS" user "Ref Des/Silkscreen Top")
		(7 "B.SilkS" user "Ref Des/Silkscreen Bottom")
		(1 "F.Mask" user "Board Geometry/Soldermask Top")
		(3 "B.Mask" user "Board Geometry/Soldermask Bottom")
		(17 "Dwgs.User" user "User.Drawings")
		(19 "Cmts.User" user "User.Comments")
		(21 "Eco1.User" user "User.Eco1")
		(23 "Eco2.User" user "User.Eco2")
		(25 "Edge.Cuts" user "Board Geometry/Outline")
		(27 "Margin" user)
		(31 "F.CrtYd" user "Package Geometry/Place Bound Top")
		(29 "B.CrtYd" user "Package Geometry/Place Bound Bottom")
		(35 "F.Fab" user "Ref Des/Assembly Top")
		(33 "B.Fab" user "Ref Des/Assembly Bottom")
	)
	(footprint ""
		(layer "F.Cu")
		(at 43.7896 -136.2456 90)
		(property "Reference" "PC90"
			(at 0 0 90)
			(layer "F.SilkS")
			(hide yes)
			(effects
				(font
					(size 1.27 1.27)
				)
			)
		)
		(property "Value" "SCD1U25V2KX-GP"
			(at 1.1811 -2.7051 90)
			(unlocked yes)
			(layer "F.Fab")
			(hide yes)
			(effects
				(font
					(size 1.016 1.016)
					(thickness 0.1524)
				)
			)
		)
		(property "Device Type" "C402H22"
			(at 1.1811 -4.2291 90)
			(unlocked yes)
			(layer "F.Fab")
			(hide yes)
			(effects
				(font
					(size 1.016 1.016)
					(thickness 0.1524)
				)
			)
		)
		(duplicate_pad_numbers_are_jumpers no)
		(fp_rect
			(start -0.4318 0.9525)
			(end 0.4318 -0.9525)
			(stroke
				(width 0)
				(type default)
			)
			(fill no)
			(layer "F.CrtYd")
		)
		(fp_rect
			(start -0.4318 0.9525)
			(end 0.4318 -0.9525)
			(stroke
				(width 0)
				(type default)
			)
			(fill no)
			(layer "F.Fab")
		)
		(pad "1" smd custom
			(at 0 -0.4445 90)
			(size 0.1524 0.1524)
			(layers "F.Cu" "F.Mask" "F.Paste")
			(net "P12VL_2490_VCC")
			(options
				(clearance outline)
				(anchor circle)
			)
			(primitives
				(gr_poly
					(pts
						(arc
							(start 0.3048 -0.2032)
							(mid 0.275042 -0.275042)
							(end 0.2032 -0.3048)
						)
						(arc
							(start -0.2032 -0.3048)
							(mid -0.275042 -0.275042)
							(end -0.3048 -0.2032)
						)
						(arc
							(start -0.3048 0.2032)
							(mid -0.275042 0.275042)
							(end -0.2032 0.3048)
						)
						(arc
							(start 0.2032 0.3048)
							(mid 0.275042 0.275042)
							(end 0.3048 0.2032)
						)
					)
					(width 0)
					(fill yes)
				)
			)
		)
		(pad "2" smd custom
			(at 0 0.4445 90)
			(size 0.1524 0.1524)
			(layers "F.Cu" "F.Mask" "F.Paste")
			(net "GND")
			(options
				(clearance outline)
				(anchor circle)
			)
			(primitives
				(gr_poly
					(pts
						(arc
							(start 0.3048 -0.2032)
							(mid 0.275042 -0.275042)
							(end 0.2032 -0.3048)
						)
						(arc
							(start -0.2032 -0.3048)
							(mid -0.275042 -0.275042)
							(end -0.3048 -0.2032)
						)
						(arc
							(start -0.3048 0.2032)
							(mid -0.275042 0.275042)
							(end -0.2032 0.3048)
						)
						(arc
							(start 0.2032 0.3048)
							(mid 0.275042 0.275042)
							(end 0.3048 0.2032)
						)
					)
					(width 0)
					(fill yes)
				)
			)
		)
	)
	(footprint ""
		(layer "F.Cu")
		(at 25.654 -400.177)
		(property "Reference" "PQ1"
			(at 0 0 0)
			(layer "F.SilkS")
			(hide yes)
			(effects
				(font
					(size 1.27 1.27)
				)
			)
		)
		(property "Value" "PH0925CL-GP"
			(at -4.2799 -0.4572 0)
			(unlocked yes)
			(layer "F.Fab")
			(hide yes)
			(effects
				(font
					(size 1.016 1.016)
					(thickness 0.1524)
				)
			)
		)
		(property "Device Type" "LFPAK-5PH48-U"
			(at -4.2799 -1.9812 0)
			(unlocked yes)
			(layer "F.Fab")
			(hide yes)
			(effects
				(font
					(size 1.016 1.016)
					(thickness 0.1524)
				)
			)
		)
		(duplicate_pad_numbers_are_jumpers no)
		(fp_line
			(start -2.7559 -6.5532)
			(end -2.7559 1.0668)
			(stroke
				(width 0.1524)
				(type default)
			)
			(layer "F.SilkS")
		)
		(fp_line
			(start -2.7559 1.0668)
			(end 2.7559 1.0668)
			(stroke
				(width 0.1524)
				(type default)
			)
			(layer "F.SilkS")
		)
		(fp_line
			(start -1.7272 1.1684)
			(end -2.1082 1.1684)
			(stroke
				(width 0.3302)
				(type default)
			)
			(layer "F.SilkS")
		)
		(fp_line
			(start 2.7559 -6.5532)
			(end -2.7559 -6.5532)
			(stroke
				(width 0.1524)
				(type default)
			)
			(layer "F.SilkS")
		)
		(fp_line
			(start 2.7559 1.0668)
			(end 2.7559 -6.5532)
			(stroke
				(width 0.1524)
				(type default)
			)
			(layer "F.SilkS")
		)
		(fp_poly
			(pts
				(xy -2.3368 1.5748) (xy -1.905 1.143) (xy -1.4732 1.5748)
			)
			(stroke
				(width 0)
				(type default)
			)
			(fill yes)
			(layer "F.SilkS")
		)
		(fp_poly
			(pts
				(xy -2.5019 -4.02971) (xy -0.3302 -4.02971) (xy -0.3302 -6.30301) (xy -2.5019 -6.30301)
			)
			(stroke
				(width 0)
				(type default)
			)
			(fill yes)
			(layer "F.Paste")
		)
		(fp_poly
			(pts
				(xy -2.5019 -1.09601) (xy -0.3302 -1.09601) (xy -0.3302 -3.36931) (xy -2.5019 -3.36931)
			)
			(stroke
				(width 0)
				(type default)
			)
			(fill yes)
			(layer "F.Paste")
		)
		(fp_poly
			(pts
				(xy 0.3302 -4.02971) (xy 2.5019 -4.02971) (xy 2.5019 -6.30301) (xy 0.3302 -6.30301)
			)
			(stroke
				(width 0)
				(type default)
			)
			(fill yes)
			(layer "F.Paste")
		)
		(fp_poly
			(pts
				(xy 0.3302 -1.09601) (xy 2.5019 -1.09601) (xy 2.5019 -3.36931) (xy 0.3302 -3.36931)
			)
			(stroke
				(width 0)
				(type default)
			)
			(fill yes)
			(layer "F.Paste")
		)
		(fp_rect
			(start -2.4511 0.3048)
			(end 2.4511 -5.6896)
			(stroke
				(width 0)
				(type default)
			)
			(fill no)
			(layer "F.CrtYd")
		)
		(fp_poly
			(pts
				(xy -3.0099 1.3208) (xy -3.0099 -6.8072) (xy 3.0099 -6.8072) (xy 3.0099 -1.016) (xy 2.4511 -1.016)
				(xy 2.4511 -5.6896) (xy -2.4511 -5.6896) (xy -2.4511 0.3048) (xy 2.4511 0.3048) (xy 2.4511 -1.0033)
				(xy 3.0099 -1.0033) (xy 3.0099 1.3208)
			)
			(stroke
				(width 0)
				(type default)
			)
			(fill no)
			(layer "F.CrtYd")
		)
		(fp_rect
			(start -3.0099 1.3208)
			(end 3.0099 -6.8072)
			(stroke
				(width 0)
				(type default)
			)
			(fill no)
			(layer "F.Fab")
		)
		(pad "1" smd rect
			(at -1.905 0)
			(size 0.762 1.6256)
			(layers "F.Cu" "F.Mask" "F.Paste")
			(net "P12V")
		)
		(pad "2" smd rect
			(at -0.635 0)
			(size 0.762 1.6256)
			(layers "F.Cu" "F.Mask" "F.Paste")
			(net "P12V")
		)
		(pad "3" smd rect
			(at 0.635 0)
			(size 0.762 1.6256)
			(layers "F.Cu" "F.Mask" "F.Paste")
			(net "P12V")
		)
		(pad "4" smd rect
			(at 1.905 0)
			(size 0.762 1.6256)
			(layers "F.Cu" "F.Mask" "F.Paste")
			(net "ADM1276_GATE_DRV1")
		)
		(pad "5" smd rect
			(at 0 -3.69951)
			(size 5.0038 5.207)
			(layers "F.Cu" "F.Mask" "F.Paste")
			(net "P12V_SENSE_TRACE")
		)
	)
	(footprint ""
		(layer "F.Cu")
		(at 45.500036 -19.99996)
		(property "Reference" "H1"
			(at 0 0 0)
			(layer "F.SilkS")
			(hide yes)
			(effects
				(font
					(size 1.27 1.27)
				)
			)
		)
		(property "Value" "HOLE315R138"
			(at 0 -7.0612 0)
			(unlocked yes)
			(layer "F.Fab")
			(hide yes)
			(effects
				(font
					(size 1.016 1.016)
					(thickness 0.1524)
				)
			)
		)
		(property "Device Type" "HOLE315R138"
			(at 0 -8.5852 0)
			(unlocked yes)
			(layer "F.Fab")
			(hide yes)
			(effects
				(font
					(size 1.016 1.016)
					(thickness 0.1524)
				)
			)
		)
		(duplicate_pad_numbers_are_jumpers no)
		(fp_poly
			(pts
				(xy 0 4.3053) (xy -0.13462 4.30276) (xy -0.27051 4.29641) (xy -0.40513 4.28625) (xy -0.53975 4.27101)
				(xy -0.6731 4.25196) (xy -0.80645 4.2291) (xy -0.9398 4.20116) (xy -1.07061 4.17068) (xy -1.20142 4.13385)
				(xy -1.33096 4.09448) (xy -1.45796 4.0513) (xy -1.58496 4.00304) (xy -1.70942 3.95097) (xy -1.83261 3.89509)
				(xy -1.95453 3.83667) (xy -2.07391 3.77317) (xy -2.19202 3.70586) (xy -2.30632 3.63474) (xy -2.41935 3.56108)
				(xy -2.53111 3.48361) (xy -2.63906 3.40233) (xy -2.74447 3.31724) (xy -2.84734 3.22961) (xy -2.94767 3.13817)
				(xy -3.04419 3.04419) (xy -3.13817 2.94767) (xy -3.22961 2.84734) (xy -3.31724 2.74447) (xy -3.40233 2.63906)
				(xy -3.48361 2.53111) (xy -3.56108 2.41935) (xy -3.63474 2.30632) (xy -3.70586 2.19202) (xy -3.77317 2.07391)
				(xy -3.83667 1.95453) (xy -3.89509 1.83261) (xy -3.95097 1.70942) (xy -4.00304 1.58496) (xy -4.0513 1.45796)
				(xy -4.09448 1.33096) (xy -4.13385 1.20142) (xy -4.17068 1.07061) (xy -4.20116 0.9398) (xy -4.2291 0.80645)
				(xy -4.25196 0.6731) (xy -4.27101 0.53975) (xy -4.28625 0.40513) (xy -4.29641 0.27051) (xy -4.30276 0.13462)
				(xy -4.3053 0) (xy -4.30276 -0.13462) (xy -4.29641 -0.27051) (xy -4.28625 -0.40513) (xy -4.27101 -0.53975)
				(xy -4.25196 -0.6731) (xy -4.2291 -0.80645) (xy -4.20116 -0.9398) (xy -4.17068 -1.07061) (xy -4.13385 -1.20142)
				(xy -4.09448 -1.33096) (xy -4.0513 -1.45796) (xy -4.00304 -1.58496) (xy -3.95097 -1.70942) (xy -3.89509 -1.83261)
				(xy -3.83667 -1.95453) (xy -3.77317 -2.07391) (xy -3.70586 -2.19202) (xy -3.63474 -2.30632) (xy -3.56108 -2.41935)
				(xy -3.48361 -2.53111) (xy -3.40233 -2.63906) (xy -3.31724 -2.74447) (xy -3.22961 -2.84734) (xy -3.13817 -2.94767)
				(xy -3.04419 -3.04419) (xy -2.94767 -3.13817) (xy -2.84734 -3.22961) (xy -2.74447 -3.31724) (xy -2.63906 -3.40233)
				(xy -2.53111 -3.48361) (xy -2.41935 -3.56108) (xy -2.30632 -3.63474) (xy -2.19202 -3.70586) (xy -2.07391 -3.77317)
				(xy -1.95453 -3.83667) (xy -1.83261 -3.89509) (xy -1.70942 -3.95097) (xy -1.58496 -4.00304) (xy -1.45796 -4.0513)
				(xy -1.33096 -4.09448) (xy -1.20142 -4.13385) (xy -1.07061 -4.17068) (xy -0.9398 -4.20116) (xy -0.80645 -4.2291)
				(xy -0.6731 -4.25196) (xy -0.53975 -4.27101) (xy -0.40513 -4.28625) (xy -0.27051 -4.29641) (xy -0.13462 -4.30276)
				(xy 0 -4.3053) (xy 0.13462 -4.30276) (xy 0.27051 -4.29641) (xy 0.40513 -4.28625) (xy 0.53975 -4.27101)
				(xy 0.6731 -4.25196) (xy 0.80645 -4.2291) (xy 0.9398 -4.20116) (xy 1.07061 -4.17068) (xy 1.20142 -4.13385)
				(xy 1.33096 -4.09448) (xy 1.45796 -4.0513) (xy 1.58496 -4.00304) (xy 1.70942 -3.95097) (xy 1.83261 -3.89509)
				(xy 1.95453 -3.83667) (xy 2.07391 -3.77317) (xy 2.19202 -3.70586) (xy 2.30632 -3.63474) (xy 2.41935 -3.56108)
				(xy 2.53111 -3.48361) (xy 2.63906 -3.40233) (xy 2.74447 -3.31724) (xy 2.84734 -3.22961) (xy 2.94767 -3.13817)
				(xy 3.04419 -3.04419) (xy 3.13817 -2.94767) (xy 3.22961 -2.84734) (xy 3.31724 -2.74447) (xy 3.40233 -2.63906)
				(xy 3.48361 -2.53111) (xy 3.56108 -2.41935) (xy 3.63474 -2.30632) (xy 3.70586 -2.19202) (xy 3.77317 -2.07391)
				(xy 3.83667 -1.95453) (xy 3.89509 -1.83261) (xy 3.95097 -1.70942) (xy 4.00304 -1.58496) (xy 4.0513 -1.45796)
				(xy 4.09448 -1.33096) (xy 4.13385 -1.20142) (xy 4.17068 -1.07061) (xy 4.20116 -0.9398) (xy 4.2291 -0.80645)
				(xy 4.25196 -0.6731) (xy 4.27101 -0.53975) (xy 4.28625 -0.40513) (xy 4.29641 -0.27051) (xy 4.30276 -0.13462)
				(xy 4.3053 0) (xy 4.30276 0.13462) (xy 4.29641 0.27051) (xy 4.28625 0.40513) (xy 4.27101 0.53975)
				(xy 4.25196 0.6731) (xy 4.2291 0.80645) (xy 4.20116 0.9398) (xy 4.17068 1.07061) (xy 4.13385 1.20142)
				(xy 4.09448 1.33096) (xy 4.0513 1.45796) (xy 4.00304 1.58496) (xy 3.95097 1.70942) (xy 3.89509 1.83261)
				(xy 3.83667 1.95453) (xy 3.77317 2.07391) (xy 3.70586 2.19202) (xy 3.63474 2.30632) (xy 3.56108 2.41935)
				(xy 3.48361 2.53111) (xy 3.40233 2.63906) (xy 3.31724 2.74447) (xy 3.22961 2.84734) (xy 3.13817 2.94767)
				(xy 3.04419 3.04419) (xy 2.94767 3.13817) (xy 2.84734 3.22961) (xy 2.74447 3.31724) (xy 2.63906 3.40233)
				(xy 2.53111 3.48361) (xy 2.41935 3.56108) (xy 2.30632 3.63474) (xy 2.19202 3.70586) (xy 2.07391 3.77317)
				(xy 1.95453 3.83667) (xy 1.83261 3.89509) (xy 1.70942 3.95097) (xy 1.58496 4.00304) (xy 1.45796 4.0513)
				(xy 1.33096 4.09448) (xy 1.20142 4.13385) (xy 1.07061 4.17068) (xy 0.9398 4.20116) (xy 0.80645 4.2291)
				(xy 0.6731 4.25196) (xy 0.53975 4.27101) (xy 0.40513 4.28625) (xy 0.27051 4.29641) (xy 0.13462 4.30276)
			)
			(stroke
				(width 0)
				(type default)
			)
			(fill no)
			(layer "F.CrtYd")
		)
		(fp_poly
			(pts
				(xy 0 4.3053) (xy -0.13462 4.30276) (xy -0.27051 4.29641) (xy -0.40513 4.28625) (xy -0.53975 4.27101)
				(xy -0.6731 4.25196) (xy -0.80645 4.2291) (xy -0.9398 4.20116) (xy -1.07061 4.17068) (xy -1.20142 4.13385)
				(xy -1.33096 4.09448) (xy -1.45796 4.0513) (xy -1.58496 4.00304) (xy -1.70942 3.95097) (xy -1.83261 3.89509)
				(xy -1.95453 3.83667) (xy -2.07391 3.77317) (xy -2.19202 3.70586) (xy -2.30632 3.63474) (xy -2.41935 3.56108)
				(xy -2.53111 3.48361) (xy -2.63906 3.40233) (xy -2.74447 3.31724) (xy -2.84734 3.22961) (xy -2.94767 3.13817)
				(xy -3.04419 3.04419) (xy -3.13817 2.94767) (xy -3.22961 2.84734) (xy -3.31724 2.74447) (xy -3.40233 2.63906)
				(xy -3.48361 2.53111) (xy -3.56108 2.41935) (xy -3.63474 2.30632) (xy -3.70586 2.19202) (xy -3.77317 2.07391)
				(xy -3.83667 1.95453) (xy -3.89509 1.83261) (xy -3.95097 1.70942) (xy -4.00304 1.58496) (xy -4.0513 1.45796)
				(xy -4.09448 1.33096) (xy -4.13385 1.20142) (xy -4.17068 1.07061) (xy -4.20116 0.9398) (xy -4.2291 0.80645)
				(xy -4.25196 0.6731) (xy -4.27101 0.53975) (xy -4.28625 0.40513) (xy -4.29641 0.27051) (xy -4.30276 0.13462)
				(xy -4.3053 0) (xy -4.30276 -0.13462) (xy -4.29641 -0.27051) (xy -4.28625 -0.40513) (xy -4.27101 -0.53975)
				(xy -4.25196 -0.6731) (xy -4.2291 -0.80645) (xy -4.20116 -0.9398) (xy -4.17068 -1.07061) (xy -4.13385 -1.20142)
				(xy -4.09448 -1.33096) (xy -4.0513 -1.45796) (xy -4.00304 -1.58496) (xy -3.95097 -1.70942) (xy -3.89509 -1.83261)
				(xy -3.83667 -1.95453) (xy -3.77317 -2.07391) (xy -3.70586 -2.19202) (xy -3.63474 -2.30632) (xy -3.56108 -2.41935)
				(xy -3.48361 -2.53111) (xy -3.40233 -2.63906) (xy -3.31724 -2.74447) (xy -3.22961 -2.84734) (xy -3.13817 -2.94767)
				(xy -3.04419 -3.04419) (xy -2.94767 -3.13817) (xy -2.84734 -3.22961) (xy -2.74447 -3.31724) (xy -2.63906 -3.40233)
				(xy -2.53111 -3.48361) (xy -2.41935 -3.56108) (xy -2.30632 -3.63474) (xy -2.19202 -3.70586) (xy -2.07391 -3.77317)
				(xy -1.95453 -3.83667) (xy -1.83261 -3.89509) (xy -1.70942 -3.95097) (xy -1.58496 -4.00304) (xy -1.45796 -4.0513)
				(xy -1.33096 -4.09448) (xy -1.20142 -4.13385) (xy -1.07061 -4.17068) (xy -0.9398 -4.20116) (xy -0.80645 -4.2291)
				(xy -0.6731 -4.25196) (xy -0.53975 -4.27101) (xy -0.40513 -4.28625) (xy -0.27051 -4.29641) (xy -0.13462 -4.30276)
				(xy 0 -4.3053) (xy 0.13462 -4.30276) (xy 0.27051 -4.29641) (xy 0.40513 -4.28625) (xy 0.53975 -4.27101)
				(xy 0.6731 -4.25196) (xy 0.80645 -4.2291) (xy 0.9398 -4.20116) (xy 1.07061 -4.17068) (xy 1.20142 -4.13385)
				(xy 1.33096 -4.09448) (xy 1.45796 -4.0513) (xy 1.58496 -4.00304) (xy 1.70942 -3.95097) (xy 1.83261 -3.89509)
				(xy 1.95453 -3.83667) (xy 2.07391 -3.77317) (xy 2.19202 -3.70586) (xy 2.30632 -3.63474) (xy 2.41935 -3.56108)
				(xy 2.53111 -3.48361) (xy 2.63906 -3.40233) (xy 2.74447 -3.31724) (xy 2.84734 -3.22961) (xy 2.94767 -3.13817)
				(xy 3.04419 -3.04419) (xy 3.13817 -2.94767) (xy 3.22961 -2.84734) (xy 3.31724 -2.74447) (xy 3.40233 -2.63906)
				(xy 3.48361 -2.53111) (xy 3.56108 -2.41935) (xy 3.63474 -2.30632) (xy 3.70586 -2.19202) (xy 3.77317 -2.07391)
				(xy 3.83667 -1.95453) (xy 3.89509 -1.83261) (xy 3.95097 -1.70942) (xy 4.00304 -1.58496) (xy 4.0513 -1.45796)
				(xy 4.09448 -1.33096) (xy 4.13385 -1.20142) (xy 4.17068 -1.07061) (xy 4.20116 -0.9398) (xy 4.2291 -0.80645)
				(xy 4.25196 -0.6731) (xy 4.27101 -0.53975) (xy 4.28625 -0.40513) (xy 4.29641 -0.27051) (xy 4.30276 -0.13462)
				(xy 4.3053 0) (xy 4.30276 0.13462) (xy 4.29641 0.27051) (xy 4.28625 0.40513) (xy 4.27101 0.53975)
				(xy 4.25196 0.6731) (xy 4.2291 0.80645) (xy 4.20116 0.9398) (xy 4.17068 1.07061) (xy 4.13385 1.20142)
				(xy 4.09448 1.33096) (xy 4.0513 1.45796) (xy 4.00304 1.58496) (xy 3.95097 1.70942) (xy 3.89509 1.83261)
				(xy 3.83667 1.95453) (xy 3.77317 2.07391) (xy 3.70586 2.19202) (xy 3.63474 2.30632) (xy 3.56108 2.41935)
				(xy 3.48361 2.53111) (xy 3.40233 2.63906) (xy 3.31724 2.74447) (xy 3.22961 2.84734) (xy 3.13817 2.94767)
				(xy 3.04419 3.04419) (xy 2.94767 3.13817) (xy 2.84734 3.22961) (xy 2.74447 3.31724) (xy 2.63906 3.40233)
				(xy 2.53111 3.48361) (xy 2.41935 3.56108) (xy 2.30632 3.63474) (xy 2.19202 3.70586) (xy 2.07391 3.77317)
				(xy 1.95453 3.83667) (xy 1.83261 3.89509) (xy 1.70942 3.95097) (xy 1.58496 4.00304) (xy 1.45796 4.0513)
				(xy 1.33096 4.09448) (xy 1.20142 4.13385) (xy 1.07061 4.17068) (xy 0.9398 4.20116) (xy 0.80645 4.2291)
				(xy 0.6731 4.25196) (xy 0.53975 4.27101) (xy 0.40513 4.28625) (xy 0.27051 4.29641) (xy 0.13462 4.30276)
			)
			(stroke
				(width 0)
				(type default)
			)
			(fill no)
			(layer "F.Fab")
		)
		(pad "1" thru_hole circle
			(at 0 0)
			(size 8.001 8.001)
			(drill 3.5052)
			(layers "*.Cu" "*.Mask")
			(remove_unused_layers no)
			(net "GND")
			(clearance -1.7399)
			(thermal_gap 0.3048)
			(padstack
				(mode front_inner_back)
				(layer "Inner"
					(shape circle)
					(size 3.9116 3.9116)
					(clearance 0.3048)
				)
				(layer "B.Cu"
					(shape circle)
					(size 8.001 8.001)
					(clearance -1.7399)
				)
			)
		)
	)
)
